(kicad_pcb
	(version 20260206)
	(generator "pcbnew")
	(generator_version "10.0")
	(general
		(thickness 1.6)
		(legacy_teardrops no)
	)
	(paper "A4")
	(title_block
		(title "Bryce Canyon_R.DPB_16317-1_OCP.brd")
		(comment 1 "Bryce Canyon / footprints 23-28 of 2099")
	)
	(layers
		(0 "F.Cu" signal "TOP")
		(4 "In1.Cu" signal "L2GND")
		(6 "In2.Cu" signal "L3")
		(8 "In3.Cu" signal "L4VCC")
		(10 "In4.Cu" signal "L5VCC")
		(12 "In5.Cu" signal "L6")
		(14 "In6.Cu" signal "L7GND")
		(2 "B.Cu" signal "BOTTOM")
		(9 "F.Adhes" user "F.Adhesive")
		(11 "B.Adhes" user "B.Adhesive")
		(13 "F.Paste" user "Package Geometry/Pastemask Top")
		(15 "B.Paste" user "Package Geometry/Pastemask Bottom")
		(5 "F.SilkS" user "Ref Des/Silkscreen Top")
		(7 "B.SilkS" user "Ref Des/Silkscreen Bottom")
		(1 "F.Mask" user "Board Geometry/Soldermask Top")
		(3 "B.Mask" user "Board Geometry/Soldermask Bottom")
		(17 "Dwgs.User" user "User.Drawings")
		(19 "Cmts.User" user "User.Comments")
		(21 "Eco1.User" user "User.Eco1")
		(23 "Eco2.User" user "User.Eco2")
		(25 "Edge.Cuts" user "Board Geometry/Outline")
		(27 "Margin" user)
		(31 "F.CrtYd" user "Package Geometry/Place Bound Top")
		(29 "B.CrtYd" user "Package Geometry/Place Bound Bottom")
		(35 "F.Fab" user "Ref Des/Assembly Top")
		(33 "B.Fab" user "Ref Des/Assembly Bottom")
	)
	(footprint ""
		(layer "F.Cu")
		(at 218.403932 -353.794568 90)
		(property "Reference" "C552"
			(at 0 0 90)
			(layer "F.SilkS")
			(hide yes)
			(effects
				(font
					(size 1.27 1.27)
				)
			)
		)
		(property "Value" "SCD033U50V3KX-1GP"
			(at 0 -2.8194 90)
			(unlocked yes)
			(layer "F.Fab")
			(hide yes)
			(effects
				(font
					(size 1.016 1.016)
					(thickness 0.1524)
				)
			)
		)
		(property "Device Type" "C603H36"
			(at 0 -4.3434 90)
			(unlocked yes)
			(layer "F.Fab")
			(hide yes)
			(effects
				(font
					(size 1.016 1.016)
					(thickness 0.1524)
				)
			)
		)
		(duplicate_pad_numbers_are_jumpers no)
		(fp_line
			(start 0.508 0)
			(end -0.508 0)
			(stroke
				(width 0.2032)
				(type default)
			)
			(layer "F.SilkS")
		)
		(fp_rect
			(start -0.5842 1.3335)
			(end 0.5842 -1.3335)
			(stroke
				(width 0)
				(type default)
			)
			(fill no)
			(layer "F.CrtYd")
		)
		(fp_rect
			(start -0.5842 1.3335)
			(end 0.5842 -1.3335)
			(stroke
				(width 0)
				(type default)
			)
			(fill no)
			(layer "F.Fab")
		)
		(pad "1" smd custom
			(at 0 -0.762 90)
			(size 0.2159 0.2159)
			(layers "F.Cu" "F.Mask" "F.Paste")
			(net "MB0_CM_GATE_C")
			(options
				(clearance outline)
				(anchor circle)
			)
			(primitives
				(gr_poly
					(pts
						(arc
							(start -0.3302 -0.4318)
							(mid -0.402042 -0.402042)
							(end -0.4318 -0.3302)
						)
						(arc
							(start -0.4318 0.3302)
							(mid -0.402042 0.402042)
							(end -0.3302 0.4318)
						)
						(arc
							(start 0.3302 0.4318)
							(mid 0.402042 0.402042)
							(end 0.4318 0.3302)
						)
						(arc
							(start 0.4318 -0.3302)
							(mid 0.402042 -0.402042)
							(end 0.3302 -0.4318)
						)
					)
					(width 0)
					(fill yes)
				)
			)
		)
		(pad "2" smd custom
			(at 0 0.762 90)
			(size 0.2159 0.2159)
			(layers "F.Cu" "F.Mask" "F.Paste")
			(net "GND")
			(options
				(clearance outline)
				(anchor circle)
			)
			(primitives
				(gr_poly
					(pts
						(arc
							(start -0.3302 -0.4318)
							(mid -0.402042 -0.402042)
							(end -0.4318 -0.3302)
						)
						(arc
							(start -0.4318 0.3302)
							(mid -0.402042 0.402042)
							(end -0.3302 0.4318)
						)
						(arc
							(start 0.3302 0.4318)
							(mid 0.402042 0.402042)
							(end 0.4318 0.3302)
						)
						(arc
							(start 0.4318 -0.3302)
							(mid 0.402042 -0.402042)
							(end 0.3302 -0.4318)
						)
					)
					(width 0)
					(fill yes)
				)
			)
		)
	)
	(footprint ""
		(layer "F.Cu")
		(at 303.503076 -334.462882)
		(property "Reference" "U12"
			(at 0 0 0)
			(layer "F.SilkS")
			(hide yes)
			(effects
				(font
					(size 1.27 1.27)
				)
			)
		)
		(property "Value" "NCT7368S-GP"
			(at 4.0259 1.5748 0)
			(unlocked yes)
			(layer "F.Fab")
			(hide yes)
			(effects
				(font
					(size 1.016 1.016)
					(thickness 0.1524)
				)
			)
		)
		(property "Device Type" "SOIC8-G3627H69"
			(at 4.0259 0.0508 0)
			(unlocked yes)
			(layer "F.Fab")
			(hide yes)
			(effects
				(font
					(size 1.016 1.016)
					(thickness 0.1524)
				)
			)
		)
		(duplicate_pad_numbers_are_jumpers no)
		(fp_line
			(start -2.8829 -3.6322)
			(end 2.7178 -3.6322)
			(stroke
				(width 0.1524)
				(type default)
			)
			(layer "F.SilkS")
		)
		(fp_line
			(start -2.8829 -0.6223)
			(end -2.2479 0.0127)
			(stroke
				(width 0.1524)
				(type default)
			)
			(layer "F.SilkS")
		)
		(fp_line
			(start -2.8829 0.6477)
			(end -2.8829 -0.6223)
			(stroke
				(width 0.1524)
				(type default)
			)
			(layer "F.SilkS")
		)
		(fp_line
			(start -2.8829 3.6322)
			(end -2.8829 -3.6322)
			(stroke
				(width 0.1524)
				(type default)
			)
			(layer "F.SilkS")
		)
		(fp_line
			(start -2.7051 3.6322)
			(end -2.7051 1.5494)
			(stroke
				(width 0.508)
				(type default)
			)
			(layer "F.SilkS")
		)
		(fp_line
			(start -2.2479 0.0127)
			(end -2.8829 0.6477)
			(stroke
				(width 0.1524)
				(type default)
			)
			(layer "F.SilkS")
		)
		(fp_line
			(start 2.7178 -3.6322)
			(end 2.7178 3.6322)
			(stroke
				(width 0.1524)
				(type default)
			)
			(layer "F.SilkS")
		)
		(fp_line
			(start 2.7178 3.6322)
			(end -2.8829 3.6322)
			(stroke
				(width 0.1524)
				(type default)
			)
			(layer "F.SilkS")
		)
		(fp_poly
			(pts
				(xy -2.1209 2.9972) (xy -2.1209 1.9558) (xy -2.4511 1.9558) (xy -2.4511 -1.9558) (xy -2.1209 -1.9558)
				(xy -2.1209 -2.9972) (xy 2.1209 -2.9972) (xy 2.1209 -1.9558) (xy 2.4511 -1.9558) (xy 2.4511 1.9558)
				(xy 2.1209 1.9558) (xy 2.1209 2.9972)
			)
			(stroke
				(width 0)
				(type default)
			)
			(fill no)
			(layer "F.CrtYd")
		)
		(fp_poly
			(pts
				(xy -2.9591 3.8862) (xy -2.9591 -3.8862) (xy 2.9591 -3.8862) (xy 2.9591 1.95072) (xy 2.4511 1.95072)
				(xy 2.4511 -1.9558) (xy 2.1209 -1.9558) (xy 2.1209 -2.9972) (xy -2.1209 -2.9972) (xy -2.1209 -1.9558)
				(xy -2.4511 -1.9558) (xy -2.4511 1.9558) (xy -2.1209 1.9558) (xy -2.1209 2.9972) (xy 2.1209 2.9972)
				(xy 2.1209 1.9558) (xy 2.9591 1.9558) (xy 2.9591 3.8862)
			)
			(stroke
				(width 0)
				(type default)
			)
			(fill no)
			(layer "F.CrtYd")
		)
		(fp_rect
			(start -2.9591 3.8862)
			(end 2.9591 -3.8862)
			(stroke
				(width 0)
				(type default)
			)
			(fill no)
			(layer "F.Fab")
		)
		(pad "1" smd rect
			(at -1.905 2.5527)
			(size 0.635 1.651)
			(layers "F.Cu" "F.Mask" "F.Paste")
			(net "P3V3_IN")
		)
		(pad "2" smd rect
			(at -0.635 2.5527)
			(size 0.635 1.651)
			(layers "F.Cu" "F.Mask" "F.Paste")
			(net "PWM_SCC_A_ZONE_C")
		)
		(pad "3" smd rect
			(at 0.635 2.5527)
			(size 0.635 1.651)
			(layers "F.Cu" "F.Mask" "F.Paste")
			(net "PWM_BMC_A_ZONE_C")
		)
		(pad "4" smd rect
			(at 1.905 2.5527)
			(size 0.635 1.651)
			(layers "F.Cu" "F.Mask" "F.Paste")
			(net "PWM_BMC_B_ZONE_C")
		)
		(pad "5" smd rect
			(at 1.905 -2.5527)
			(size 0.635 1.651)
			(layers "F.Cu" "F.Mask" "F.Paste")
			(net "PWM_CAMP_SEL1")
		)
		(pad "6" smd rect
			(at 0.635 -2.5527)
			(size 0.635 1.651)
			(layers "F.Cu" "F.Mask" "F.Paste")
			(net "THERMHOT#_C")
		)
		(pad "7" smd rect
			(at -0.635 -2.5527)
			(size 0.635 1.651)
			(layers "F.Cu" "F.Mask" "F.Paste")
			(net "PWM_OUT_C_R")
		)
		(pad "8" smd rect
			(at -1.905 -2.5527)
			(size 0.635 1.651)
			(layers "F.Cu" "F.Mask" "F.Paste")
			(net "PWM_SCC_B_ZONE_C")
		)
		(pad "9" smd rect
			(at 0 0)
			(size 3.6068 2.6924)
			(layers "F.Cu" "F.Mask" "F.Paste")
			(net "GND")
		)
	)
	(footprint ""
		(layer "F.Cu")
		(at 398.907 -128.651 180)
		(property "Reference" "R540"
			(at 0 0 180)
			(layer "F.SilkS")
			(hide yes)
			(effects
				(font
					(size 1.27 1.27)
				)
			)
		)
		(property "Value" "0R2J-2-GP"
			(at 0.064008 -3.993896 180)
			(unlocked yes)
			(layer "F.Fab")
			(hide yes)
			(effects
				(font
					(size 1.016 1.016)
					(thickness 0.1524)
				)
			)
		)
		(property "Device Type" "R402H16"
			(at 0.064008 -5.517896 180)
			(unlocked yes)
			(layer "F.Fab")
			(hide yes)
			(effects
				(font
					(size 1.016 1.016)
					(thickness 0.1524)
				)
			)
		)
		(duplicate_pad_numbers_are_jumpers no)
		(fp_line
			(start 0.508 -0.9398)
			(end -0.508 -0.9398)
			(stroke
				(width 0.1524)
				(type default)
			)
			(layer "F.SilkS")
		)
		(fp_line
			(start -0.508 -0.9398)
			(end -0.508 0.9398)
			(stroke
				(width 0.1524)
				(type default)
			)
			(layer "F.SilkS")
		)
		(fp_rect
			(start -0.508 0.9398)
			(end 0.508 -0.9398)
			(stroke
				(width 0)
				(type default)
			)
			(fill no)
			(layer "F.CrtYd")
		)
		(fp_rect
			(start -0.508 0.9398)
			(end 0.508 -0.9398)
			(stroke
				(width 0)
				(type default)
			)
			(fill no)
			(layer "F.Fab")
		)
		(pad "1" smd custom
			(at 0 -0.4445 180)
			(size 0.1397 0.1397)
			(layers "F.Cu" "F.Mask" "F.Paste")
			(net "DRIVE_B_20_PWR")
			(options
				(clearance outline)
				(anchor circle)
			)
			(primitives
				(gr_poly
					(pts
						(arc
							(start -0.1778 -0.2794)
							(mid -0.249642 -0.249642)
							(end -0.2794 -0.1778)
						)
						(arc
							(start -0.2794 0.1778)
							(mid -0.249642 0.249642)
							(end -0.1778 0.2794)
						)
						(arc
							(start 0.1778 0.2794)
							(mid 0.249642 0.249642)
							(end 0.2794 0.1778)
						)
						(arc
							(start 0.2794 -0.1778)
							(mid 0.249642 -0.249642)
							(end 0.1778 -0.2794)
						)
					)
					(width 0)
					(fill yes)
				)
			)
		)
		(pad "2" smd custom
			(at 0 0.4445 180)
			(size 0.1397 0.1397)
			(layers "F.Cu" "F.Mask" "F.Paste")
			(net "SW_PWR_R_HDD20")
			(options
				(clearance outline)
				(anchor circle)
			)
			(primitives
				(gr_poly
					(pts
						(arc
							(start -0.1778 -0.2794)
							(mid -0.249642 -0.249642)
							(end -0.2794 -0.1778)
						)
						(arc
							(start -0.2794 0.1778)
							(mid -0.249642 0.249642)
							(end -0.1778 0.2794)
						)
						(arc
							(start 0.1778 0.2794)
							(mid 0.249642 0.249642)
							(end 0.2794 0.1778)
						)
						(arc
							(start 0.2794 -0.1778)
							(mid 0.249642 -0.249642)
							(end 0.1778 -0.2794)
						)
					)
					(width 0)
					(fill yes)
				)
			)
		)
	)
	(footprint ""
		(layer "F.Cu")
		(at 340.251796 -212.390228 -90)
		(property "Reference" "R261"
			(at 0 0 270)
			(layer "F.SilkS")
			(hide yes)
			(effects
				(font
					(size 1.27 1.27)
				)
			)
		)
		(property "Value" "4K7R2F-GP"
			(at 0.064008 -3.993896 270)
			(unlocked yes)
			(layer "F.Fab")
			(hide yes)
			(effects
				(font
					(size 1.016 1.016)
					(thickness 0.1524)
				)
			)
		)
		(property "Device Type" "R402H16"
			(at 0.064008 -5.517896 270)
			(unlocked yes)
			(layer "F.Fab")
			(hide yes)
			(effects
				(font
					(size 1.016 1.016)
					(thickness 0.1524)
				)
			)
		)
		(duplicate_pad_numbers_are_jumpers no)
		(fp_line
			(start -0.508 -0.9398)
			(end -0.508 0.9398)
			(stroke
				(width 0.1524)
				(type default)
			)
			(layer "F.SilkS")
		)
		(fp_line
			(start 0.508 -0.9398)
			(end -0.508 -0.9398)
			(stroke
				(width 0.1524)
				(type default)
			)
			(layer "F.SilkS")
		)
		(fp_rect
			(start -0.508 0.9398)
			(end 0.508 -0.9398)
			(stroke
				(width 0)
				(type default)
			)
			(fill no)
			(layer "F.CrtYd")
		)
		(fp_rect
			(start -0.508 0.9398)
			(end 0.508 -0.9398)
			(stroke
				(width 0)
				(type default)
			)
			(fill no)
			(layer "F.Fab")
		)
		(pad "1" smd custom
			(at 0 -0.4445 270)
			(size 0.1397 0.1397)
			(layers "F.Cu" "F.Mask" "F.Paste")
			(net "DRIVE_B_7_ACT")
			(options
				(clearance outline)
				(anchor circle)
			)
			(primitives
				(gr_poly
					(pts
						(arc
							(start -0.1778 -0.2794)
							(mid -0.249642 -0.249642)
							(end -0.2794 -0.1778)
						)
						(arc
							(start -0.2794 0.1778)
							(mid -0.249642 0.249642)
							(end -0.1778 0.2794)
						)
						(arc
							(start 0.1778 0.2794)
							(mid 0.249642 0.249642)
							(end 0.2794 0.1778)
						)
						(arc
							(start 0.2794 -0.1778)
							(mid 0.249642 -0.249642)
							(end 0.1778 -0.2794)
						)
					)
					(width 0)
					(fill yes)
				)
			)
		)
		(pad "2" smd custom
			(at 0 0.4445 270)
			(size 0.1397 0.1397)
			(layers "F.Cu" "F.Mask" "F.Paste")
			(net "GND")
			(options
				(clearance outline)
				(anchor circle)
			)
			(primitives
				(gr_poly
					(pts
						(arc
							(start -0.1778 -0.2794)
							(mid -0.249642 -0.249642)
							(end -0.2794 -0.1778)
						)
						(arc
							(start -0.2794 0.1778)
							(mid -0.249642 0.249642)
							(end -0.1778 0.2794)
						)
						(arc
							(start 0.1778 0.2794)
							(mid 0.249642 0.249642)
							(end 0.2794 0.1778)
						)
						(arc
							(start 0.2794 -0.1778)
							(mid 0.249642 -0.249642)
							(end 0.1778 -0.2794)
						)
					)
					(width 0)
					(fill yes)
				)
			)
		)
	)
	(footprint ""
		(layer "F.Cu")
		(at 241.681 -311.912 180)
		(property "Reference" "R1093"
			(at 0 0 180)
			(layer "F.SilkS")
			(hide yes)
			(effects
				(font
					(size 1.27 1.27)
				)
			)
		)
		(property "Value" "0R2J-2-GP"
			(at 0.064008 -3.993896 180)
			(unlocked yes)
			(layer "F.Fab")
			(hide yes)
			(effects
				(font
					(size 1.016 1.016)
					(thickness 0.1524)
				)
			)
		)
		(property "Device Type" "R402H16"
			(at 0.064008 -5.517896 180)
			(unlocked yes)
			(layer "F.Fab")
			(hide yes)
			(effects
				(font
					(size 1.016 1.016)
					(thickness 0.1524)
				)
			)
		)
		(duplicate_pad_numbers_are_jumpers no)
		(fp_line
			(start 0.508 -0.9398)
			(end -0.508 -0.9398)
			(stroke
				(width 0.1524)
				(type default)
			)
			(layer "F.SilkS")
		)
		(fp_line
			(start -0.508 -0.9398)
			(end -0.508 0.9398)
			(stroke
				(width 0.1524)
				(type default)
			)
			(layer "F.SilkS")
		)
		(fp_rect
			(start -0.508 0.9398)
			(end 0.508 -0.9398)
			(stroke
				(width 0)
				(type default)
			)
			(fill no)
			(layer "F.CrtYd")
		)
		(fp_rect
			(start -0.508 0.9398)
			(end 0.508 -0.9398)
			(stroke
				(width 0)
				(type default)
			)
			(fill no)
			(layer "F.Fab")
		)
		(pad "1" smd custom
			(at 0 -0.4445 180)
			(size 0.1397 0.1397)
			(layers "F.Cu" "F.Mask" "F.Paste")
			(net "MAX31790_A_ADD0")
			(options
				(clearance outline)
				(anchor circle)
			)
			(primitives
				(gr_poly
					(pts
						(arc
							(start -0.1778 -0.2794)
							(mid -0.249642 -0.249642)
							(end -0.2794 -0.1778)
						)
						(arc
							(start -0.2794 0.1778)
							(mid -0.249642 0.249642)
							(end -0.1778 0.2794)
						)
						(arc
							(start 0.1778 0.2794)
							(mid 0.249642 0.249642)
							(end 0.2794 0.1778)
						)
						(arc
							(start 0.2794 -0.1778)
							(mid 0.249642 -0.249642)
							(end 0.1778 -0.2794)
						)
					)
					(width 0)
					(fill yes)
				)
			)
		)
		(pad "2" smd custom
			(at 0 0.4445 180)
			(size 0.1397 0.1397)
			(layers "F.Cu" "F.Mask" "F.Paste")
			(net "GND")
			(options
				(clearance outline)
				(anchor circle)
			)
			(primitives
				(gr_poly
					(pts
						(arc
							(start -0.1778 -0.2794)
							(mid -0.249642 -0.249642)
							(end -0.2794 -0.1778)
						)
						(arc
							(start -0.2794 0.1778)
							(mid -0.249642 0.249642)
							(end -0.1778 0.2794)
						)
						(arc
							(start 0.1778 0.2794)
							(mid 0.249642 0.249642)
							(end 0.2794 0.1778)
						)
						(arc
							(start 0.2794 -0.1778)
							(mid 0.249642 -0.249642)
							(end 0.1778 -0.2794)
						)
					)
					(width 0)
					(fill yes)
				)
			)
		)
	)
	(footprint ""
		(layer "F.Cu")
		(at 367.284 -131.826 180)
		(property "Reference" "R524"
			(at 0 0 180)
			(layer "F.SilkS")
			(hide yes)
			(effects
				(font
					(size 1.27 1.27)
				)
			)
		)
		(property "Value" "0R2J-2-GP"
			(at 0.064008 -3.993896 180)
			(unlocked yes)
			(layer "F.Fab")
			(hide yes)
			(effects
				(font
					(size 1.016 1.016)
					(thickness 0.1524)
				)
			)
		)
		(property "Device Type" "R402H16"
			(at 0.064008 -5.517896 180)
			(unlocked yes)
			(layer "F.Fab")
			(hide yes)
			(effects
				(font
					(size 1.016 1.016)
					(thickness 0.1524)
				)
			)
		)
		(duplicate_pad_numbers_are_jumpers no)
		(fp_line
			(start 0.508 -0.9398)
			(end -0.508 -0.9398)
			(stroke
				(width 0.1524)
				(type default)
			)
			(layer "F.SilkS")
		)
		(fp_line
			(start -0.508 -0.9398)
			(end -0.508 0.9398)
			(stroke
				(width 0.1524)
				(type default)
			)
			(layer "F.SilkS")
		)
		(fp_rect
			(start -0.508 0.9398)
			(end 0.508 -0.9398)
			(stroke
				(width 0)
				(type default)
			)
			(fill no)
			(layer "F.CrtYd")
		)
		(fp_rect
			(start -0.508 0.9398)
			(end 0.508 -0.9398)
			(stroke
				(width 0)
				(type default)
			)
			(fill no)
			(layer "F.Fab")
		)
		(pad "1" smd custom
			(at 0 -0.4445 180)
			(size 0.1397 0.1397)
			(layers "F.Cu" "F.Mask" "F.Paste")
			(net "SW_HDD_G19")
			(options
				(clearance outline)
				(anchor circle)
			)
			(primitives
				(gr_poly
					(pts
						(arc
							(start -0.1778 -0.2794)
							(mid -0.249642 -0.249642)
							(end -0.2794 -0.1778)
						)
						(arc
							(start -0.2794 0.1778)
							(mid -0.249642 0.249642)
							(end -0.1778 0.2794)
						)
						(arc
							(start 0.1778 0.2794)
							(mid 0.249642 0.249642)
							(end 0.2794 0.1778)
						)
						(arc
							(start 0.2794 -0.1778)
							(mid 0.249642 -0.249642)
							(end 0.1778 -0.2794)
						)
					)
					(width 0)
					(fill yes)
				)
			)
		)
		(pad "2" smd custom
			(at 0 0.4445 180)
			(size 0.1397 0.1397)
			(layers "F.Cu" "F.Mask" "F.Paste")
			(net "SW_HDD_R19")
			(options
				(clearance outline)
				(anchor circle)
			)
			(primitives
				(gr_poly
					(pts
						(arc
							(start -0.1778 -0.2794)
							(mid -0.249642 -0.249642)
							(end -0.2794 -0.1778)
						)
						(arc
							(start -0.2794 0.1778)
							(mid -0.249642 0.249642)
							(end -0.1778 0.2794)
						)
						(arc
							(start 0.1778 0.2794)
							(mid 0.249642 0.249642)
							(end 0.2794 0.1778)
						)
						(arc
							(start 0.2794 -0.1778)
							(mid 0.249642 -0.249642)
							(end 0.1778 -0.2794)
						)
					)
					(width 0)
					(fill yes)
				)
			)
		)
	)
)
